# BASEBOARD_FAB2 (Tioga Pass) — schematic netlist excerpt (pin names and nets, part order shuffled) for the footprints in the layout excerpt that follows; sources: Cadence DE-HDL packaged netlist, KiCad conversion of Wiwynn_Tioga_Pass_MB.brd

C2T17  CAP_A  0.1UF 16V 10% X7R  pkg 0402V  page 101 : A = P3V3_STBY_MNG ; B = GND
R8D4  RES  20.0 1% CHIP  pkg 0402  page 138 : A = SMB_VR_STBY_LVC3_SCL_R1 ; B = SMB_VR_STBY_LVC3_SCL
C9N26  CAP  10UF 16V 10% X6S  pkg 0805  page 209 : A = VR_FET_SW_P12V_STBY_PVCCIN_CPU1 ; B = GND

(kicad_pcb
	(version 20260206)
	(generator "pcbnew")
	(generator_version "10.0")
	(general
		(thickness 1.6)
		(legacy_teardrops no)
	)
	(paper "A4")
	(title_block
		(title "Wiwynn_Tioga_Pass_MB.brd")
		(comment 1 "Tioga Pass / footprints 4300-4302 of 4770")
	)
	(layers
		(0 "F.Cu" signal "TOP")
		(4 "In1.Cu" signal "L2GND")
		(6 "In2.Cu" signal "L3")
		(8 "In3.Cu" signal "L4GND")
		(10 "In4.Cu" signal "L5")
		(12 "In5.Cu" signal "L6GND")
		(14 "In6.Cu" signal "L7VCC")
		(16 "In7.Cu" signal "L8VCC")
		(18 "In8.Cu" signal "L9GND")
		(20 "In9.Cu" signal "L10")
		(22 "In10.Cu" signal "L11GND")
		(24 "In11.Cu" signal "L12")
		(26 "In12.Cu" signal "L13GND")
		(2 "B.Cu" signal "BOTTOM")
		(9 "F.Adhes" user "F.Adhesive")
		(11 "B.Adhes" user "B.Adhesive")
		(13 "F.Paste" user "Package Geometry/Pastemask Top")
		(15 "B.Paste" user "Package Geometry/Pastemask Bottom")
		(5 "F.SilkS" user "Ref Des/Silkscreen Top")
		(7 "B.SilkS" user "Ref Des/Silkscreen Bottom")
		(1 "F.Mask" user "Board Geometry/Soldermask Top")
		(3 "B.Mask" user "Board Geometry/Soldermask Bottom")
		(17 "Dwgs.User" user "User.Drawings")
		(19 "Cmts.User" user "User.Comments")
		(21 "Eco1.User" user "User.Eco1")
		(23 "Eco2.User" user "User.Eco2")
		(25 "Edge.Cuts" user "Board Geometry/Outline")
		(27 "Margin" user)
		(31 "F.CrtYd" user "Package Geometry/Place Bound Top")
		(29 "B.CrtYd" user "Package Geometry/Place Bound Bottom")
		(35 "F.Fab" user "Ref Des/Assembly Top")
		(33 "B.Fab" user "Ref Des/Assembly Bottom")
	)
	(footprint ""
		(layer "B.Cu")
		(at 476.234506 -27.703018 180)
		(property "Reference" "C2T17"
			(at 0 0 0)
			(layer "B.SilkS")
			(hide yes)
			(effects
				(font
					(size 1.27 1.27)
				)
				(justify mirror)
			)
		)
		(property "Value" ""
			(at 0 0 0)
			(layer "B.Fab")
			(effects
				(font
					(size 1.27 1.27)
				)
				(justify mirror)
			)
		)
		(duplicate_pad_numbers_are_jumpers no)
		(fp_poly
			(pts
				(xy -0.3048 -0.1016) (xy -0.3048 0.9906) (xy 0.3048 0.9906) (xy 0.3048 -0.1016)
			)
			(stroke
				(width 0)
				(type default)
			)
			(fill no)
			(layer "B.CrtYd")
		)
		(fp_line
			(start 0.3048 0.9906)
			(end -0.3048 0.9906)
			(stroke
				(width 0.1)
				(type default)
			)
			(layer "B.Fab")
		)
		(fp_line
			(start 0.3048 -0.1016)
			(end 0.3048 0.9906)
			(stroke
				(width 0.1)
				(type default)
			)
			(layer "B.Fab")
		)
		(fp_line
			(start -0.3048 0.9906)
			(end -0.3048 -0.1016)
			(stroke
				(width 0.1)
				(type default)
			)
			(layer "B.Fab")
		)
		(fp_line
			(start -0.3048 -0.1016)
			(end 0.3048 -0.1016)
			(stroke
				(width 0.1)
				(type default)
			)
			(layer "B.Fab")
		)
		(pad "1" smd rect
			(at 0 0)
			(size 0.508 0.508)
			(layers "B.Cu" "B.Mask" "B.Paste")
			(net "P3V3_STBY_MNG")
		)
		(pad "2" smd rect
			(at 0 0.889)
			(size 0.508 0.508)
			(layers "B.Cu" "B.Mask" "B.Paste")
			(net "GND")
		)
		(zone
			(layer "B.Cu")
			(hatch none 0.5)
			(connect_pads
				(clearance 0)
			)
			(min_thickness 0.25)
			(keepout
				(tracks not_allowed)
				(vias allowed)
				(pads allowed)
				(copperpour not_allowed)
				(footprints allowed)
			)
			(placement
				(enabled no)
				(sheetname "")
			)
			(fill
				(thermal_gap 0.5)
				(thermal_bridge_width 0.5)
				(island_removal_mode 0)
			)
			(polygon
				(pts
					(xy 475.980506 -28.338018) (xy 476.488506 -28.338018) (xy 476.488506 -27.957018) (xy 475.980506 -27.957018)
				)
			)
		)
		(zone
			(layer "B.Cu")
			(hatch none 0.5)
			(connect_pads
				(clearance 0)
			)
			(min_thickness 0.25)
			(keepout
				(tracks allowed)
				(vias not_allowed)
				(pads allowed)
				(copperpour not_allowed)
				(footprints allowed)
			)
			(placement
				(enabled no)
				(sheetname "")
			)
			(fill
				(thermal_gap 0.5)
				(thermal_bridge_width 0.5)
				(island_removal_mode 0)
			)
			(polygon
				(pts
					(xy 475.980506 -27.957018) (xy 476.488506 -27.957018) (xy 476.488506 -28.338018) (xy 475.980506 -28.338018)
				)
			)
		)
	)
	(footprint ""
		(layer "B.Cu")
		(at 397.637 -88.2142)
		(property "Reference" "R8D4"
			(at 0 0 0)
			(layer "B.SilkS")
			(hide yes)
			(effects
				(font
					(size 1.27 1.27)
				)
				(justify mirror)
			)
		)
		(property "Value" ""
			(at 0 0 0)
			(layer "B.Fab")
			(effects
				(font
					(size 1.27 1.27)
				)
				(justify mirror)
			)
		)
		(duplicate_pad_numbers_are_jumpers no)
		(fp_poly
			(pts
				(xy 0.2794 -0.1016) (xy -0.2794 -0.1016) (xy -0.2794 0.9906) (xy 0.2794 0.9906)
			)
			(stroke
				(width 0)
				(type default)
			)
			(fill no)
			(layer "B.CrtYd")
		)
		(fp_line
			(start -0.2794 -0.1016)
			(end 0.2794 -0.1016)
			(stroke
				(width 0.1)
				(type default)
			)
			(layer "B.Fab")
		)
		(fp_line
			(start -0.2794 0.9906)
			(end -0.2794 -0.1016)
			(stroke
				(width 0.1)
				(type default)
			)
			(layer "B.Fab")
		)
		(fp_line
			(start 0.2794 -0.1016)
			(end 0.2794 0.9906)
			(stroke
				(width 0.1)
				(type default)
			)
			(layer "B.Fab")
		)
		(fp_line
			(start 0.2794 0.9906)
			(end -0.2794 0.9906)
			(stroke
				(width 0.1)
				(type default)
			)
			(layer "B.Fab")
		)
		(pad "1" smd rect
			(at 0 0 180)
			(size 0.508 0.508)
			(layers "B.Cu" "B.Mask" "B.Paste")
			(net "SMB_VR_STBY_LVC3_SCL_R1")
		)
		(pad "2" smd rect
			(at 0 0.889 180)
			(size 0.508 0.508)
			(layers "B.Cu" "B.Mask" "B.Paste")
			(net "SMB_VR_STBY_LVC3_SCL")
		)
		(zone
			(layer "B.Cu")
			(hatch none 0.5)
			(connect_pads
				(clearance 0)
			)
			(min_thickness 0.25)
			(keepout
				(tracks allowed)
				(vias not_allowed)
				(pads allowed)
				(copperpour not_allowed)
				(footprints allowed)
			)
			(placement
				(enabled no)
				(sheetname "")
			)
			(fill
				(thermal_gap 0.5)
				(thermal_bridge_width 0.5)
				(island_removal_mode 0)
			)
			(polygon
				(pts
					(xy 397.891 -87.9602) (xy 397.383 -87.9602) (xy 397.383 -87.5792) (xy 397.891 -87.5792)
				)
			)
		)
		(zone
			(layer "B.Cu")
			(hatch none 0.5)
			(connect_pads
				(clearance 0)
			)
			(min_thickness 0.25)
			(keepout
				(tracks not_allowed)
				(vias allowed)
				(pads allowed)
				(copperpour not_allowed)
				(footprints allowed)
			)
			(placement
				(enabled no)
				(sheetname "")
			)
			(fill
				(thermal_gap 0.5)
				(thermal_bridge_width 0.5)
				(island_removal_mode 0)
			)
			(polygon
				(pts
					(xy 397.891 -87.5792) (xy 397.383 -87.5792) (xy 397.383 -87.9602) (xy 397.891 -87.9602)
				)
			)
		)
	)
	(footprint ""
		(layer "B.Cu")
		(at 32.832802 -90.809064 90)
		(property "Reference" "C9N26"
			(at 0 0 90)
			(layer "B.SilkS")
			(hide yes)
			(effects
				(font
					(size 1.27 1.27)
				)
				(justify mirror)
			)
		)
		(property "Value" ""
			(at 0 0 90)
			(layer "B.Fab")
			(effects
				(font
					(size 1.27 1.27)
				)
				(justify mirror)
			)
		)
		(duplicate_pad_numbers_are_jumpers no)
		(fp_poly
			(pts
				(xy 0.7239 -0.2159) (xy -0.7239 -0.2159) (xy -0.7239 1.9939) (xy 0.7239 1.9939)
			)
			(stroke
				(width 0)
				(type default)
			)
			(fill no)
			(layer "B.CrtYd")
		)
		(fp_line
			(start 0.7239 -0.2159)
			(end 0.7239 1.9939)
			(stroke
				(width 0.1)
				(type default)
			)
			(layer "B.Fab")
		)
		(fp_line
			(start -0.7239 -0.2159)
			(end 0.7239 -0.2159)
			(stroke
				(width 0.1)
				(type default)
			)
			(layer "B.Fab")
		)
		(fp_line
			(start 0.7239 1.9939)
			(end -0.7239 1.9939)
			(stroke
				(width 0.1)
				(type default)
			)
			(layer "B.Fab")
		)
		(fp_line
			(start -0.7239 1.9939)
			(end -0.7239 -0.2159)
			(stroke
				(width 0.1)
				(type default)
			)
			(layer "B.Fab")
		)
		(pad "1" smd rect
			(at 0 0 270)
			(size 1.27 1.016)
			(layers "B.Cu" "B.Mask" "B.Paste")
			(net "VR_FET_SW_P12V_STBY_PVCCIN_CPU1")
		)
		(pad "2" smd rect
			(at 0 1.778 270)
			(size 1.27 1.016)
			(layers "B.Cu" "B.Mask" "B.Paste")
			(net "GND")
		)
		(zone
			(layer "B.Cu")
			(hatch none 0.5)
			(connect_pads
				(clearance 0)
			)
			(min_thickness 0.25)
			(keepout
				(tracks not_allowed)
				(vias allowed)
				(pads allowed)
				(copperpour not_allowed)
				(footprints allowed)
			)
			(placement
				(enabled no)
				(sheetname "")
			)
			(fill
				(thermal_gap 0.5)
				(thermal_bridge_width 0.5)
				(island_removal_mode 0)
			)
			(polygon
				(pts
					(xy 33.340802 -91.444064) (xy 33.340802 -90.174064) (xy 34.102802 -90.174064) (xy 34.102802 -91.444064)
				)
			)
		)
	)
)
